FILE_TYPE = CONNECTIVITY;
{Allegro Design Entry HDL 17.4-2019 S026 (4007227) 1/17/2022}
"PAGE_NUMBER" = 246;
0"NC";
1"GND\g";
2"GND\g";
3"P3V3_AUX\g";
4"P3V3_AUX\g";
5"GND\g";
6"GND\g";
7"GPU_PEX_STRAP0_R"CDS_PHYS_NET_NAME"GPU_PEX_STRAP0_R";
8"GPU_BASE_ID1_R"CDS_PHYS_NET_NAME"GPU_BASE_ID1_R";
9"GPU_PRSNT_N_ISO_R1";
10"GPU_PEX_STRAP1_R"CDS_PHYS_NET_NAME"GPU_PEX_STRAP1_R";
11"SMB_IOEXP_3V3AUX_SDA_R1"CDS_PHYS_NET_NAME"SMB_IOEXP_3V3AUX_SDA_R1";
12"SMB_IOEXP_3V3AUX_SCL_R1"CDS_PHYS_NET_NAME"SMB_IOEXP_3V3AUX_SCL_R1";
13"RST_USB_HUB_N"$PHYS_NET_NAME"RST_PCIE_M2_N"CDS_PHYS_NET_NAME"RST_USB_HUB_N";
14"RST_SWB_BIC_N"$PHYS_NET_NAME"RST_PCIE_M2_N"CDS_PHYS_NET_NAME"RST_SWB_BIC_N";
15"TP_TCA9539_0_P0_2"$PHYS_NET_NAME"RST_PCIE_M2_N"CDS_PHYS_NET_NAME"TP_TCA9539_0_P0_2";
16"TP_TCA9539_0_P0_3"$PHYS_NET_NAME"RST_PCIE_M2_N"CDS_PHYS_NET_NAME"TP_TCA9539_0_P0_3";
17"PRSNT_CABLE_GPU_B3_ISO_R1_N";
18"PRSNT_CABLE_GPU_A1_ISO_R1_N";
19"GPU_PEX_STRAP1_R"$PHYS_NET_NAME"RST_PCIE_M2_N"CDS_PHYS_NET_NAME"GPU_PEX_STRAP1_R";
20"GPU_PEX_STRAP0_R"$PHYS_NET_NAME"RST_PCIE_M2_N"CDS_PHYS_NET_NAME"GPU_PEX_STRAP0_R";
21"GPU_BASE_ID1_R"$PHYS_NET_NAME"RST_PCIE_M2_N"CDS_PHYS_NET_NAME"GPU_BASE_ID1_R";
22"GPU_BASE_ID0_R"$PHYS_NET_NAME"RST_PCIE_M2_N"CDS_PHYS_NET_NAME"GPU_BASE_ID0_R";
23"PRSNT_CABLE_SWB_B1_ISO_R_N";
24"PRSNT_CABLE_GPU_A2_ISO_R1_N";
25"SMB_IOEXP_3V3AUX_SDA_R1"CDS_PHYS_NET_NAME"SMB_IOEXP_3V3AUX_SDA_R1";
26"SMB_IOEXP_3V3AUX_SCL_R1"CDS_PHYS_NET_NAME"SMB_IOEXP_3V3AUX_SCL_R1";
27"TCA9539_0_ADD0"$PHYS_NET_NAME"RST_PCIE_M2_N"CDS_PHYS_NET_NAME"TCA9539_0_ADD0";
28"PRSNT_CABLE_GPU_A3_ISO_R_N";
29"P3V3_AUX\g"VOLTAGE"3.3";
30"RST_SWB_BIC_R_N"CDS_PHYS_NET_NAME"RST_SWB_BIC_R_N";
31"GPU_BASE_ID0_R"CDS_PHYS_NET_NAME"GPU_BASE_ID0_R";
32"PRSNT_CABLE_SWB_B2_ISO_R_N";
33"PRSNT_CABLE_GPU_A2_ISO_R1_N";
34"PRSNT_CABLE_GPU_A3_ISO_R_N";
35"PRSNT_CABLE_GPU_B3_ISO_R1_N";
36"PRSNT_SWB_ISO_R1_N";
37"PRSNT_CABLE_SWB_B1_ISO_R_N";
38"PRSNT_CABLE_GPU_A1_ISO_R1_N";
39"GPU_BASE_ID1"CDS_PHYS_NET_NAME"GPU_BASE_ID1";
40"SMB_IOEXP_3V3AUX_SDA"CDS_PHYS_NET_NAME"SMB_IOEXP_3V3AUX_SDA";
41"GPU_BASE_ID0"CDS_PHYS_NET_NAME"GPU_BASE_ID0";
42"RST_SWB_BIC_N"CDS_PHYS_NET_NAME"RST_SWB_BIC_N";
43"SMB_IOEXP_3V3AUX_SCL"CDS_PHYS_NET_NAME"SMB_IOEXP_3V3AUX_SCL";
44"GPU_PEX_STRAP1"CDS_PHYS_NET_NAME"GPU_PEX_STRAP1";
45"GPU_PEX_STRAP0"CDS_PHYS_NET_NAME"GPU_PEX_STRAP0";
46"PRSNT_CABLE_SWB_B1_ISO_N";
47"GPU_PRSNT_N_ISO";
48"PRSNT_CABLE_GPU_B3_ISO_N";
49"PRSNT_CABLE_GPU_A3_ISO_N";
50"PRSNT_CABLE_GPU_A1_ISO_N";
51"PRSNT_SWB_ISO_N";
52"PRSNT_CABLE_SWB_B2_ISO_N";
53"PRSNT_CABLE_GPU_A2_ISO_N";
54"PRSNT_CABLE_SWB_B2_ISO_R_N";
55"TCA9539_0_ADD1"$PHYS_NET_NAME"RST_PCIE_M2_N"CDS_PHYS_NET_NAME"TCA9539_0_ADD1";
56"GPU_PRSNT_N_ISO_R1";
57"PRSNT_SWB_ISO_R1_N";
58"PU_U181_INT";
59"PU_RST_SMB_U181_N"CDS_PHYS_NET_NAME"PU_RST_SMB_U181_N";
60"RST_SMB_SWITCH_N"CDS_PHYS_NET_NAME"RST_SMB_SWITCH_N";
61"TCA9539_0_ADD0"CDS_PHYS_NET_NAME"TCA9539_0_ADD0";
62"P3V3_AUX\g";
63"TCA9539_0_ADD1"CDS_PHYS_NET_NAME"TCA9539_0_ADD1";
%"UNIVERSAL_GND"
"1","(-7175,2300)","0","pure_quanta_power","I1";
;
CDS_LIB"pure_quanta_power"
HDL_POWER"GND";
"A"1;
%"Q_RES"
"2","(-7175,2525)","0","pure_quanta","I2";
;
LOCATION"R2694"
$SEC"1"
CDS_SEC"1"
MATERIAL"CHIP"
VALUE"1K"
TOLERANCE"1%"
WATTAGE"1/16W"
PACK_TYPE"0402LF"
CDS_LIB"pure_quanta"
PART_NUMBER"CS21002FB06";
"A"
$PN"1"63;
"B"
$PN"2"1;
%"UNIVERSAL_GND"
"1","(-4950,4175)","0","pure_quanta_power","I25";
;
CDS_LIB"pure_quanta_power"
HDL_POWER"GND";
"A"2;
%"Q_RES"
"2","(-7175,3125)","0","pure_quanta","I3";
;
LOCATION"R2693"
$SEC"1"
CDS_SEC"1"
TOLERANCE"1%"
WATTAGE"1/16W"
VALUE"1K"
MATERIAL"EMPTY"
PACK_TYPE"0402LF"
CDS_LIB"pure_quanta"
PART_NUMBER"CS21002FB06";
"A"
$PN"1"62;
"B"
$PN"2"63;
%"Q_RES"
"1","(-6275,5300)","0","pure_quanta","I31";
;
LOCATION"R2922"
$SEC"1"
CDS_SEC"1"
MATERIAL"CHIP"
TOLERANCE"5%"
VALUE"0"
CDS_LIB"pure_quanta"
WATTAGE"1/16W"
PACK_TYPE"0402LF"
PART_NUMBER"CS00002JB13";
"B"
$PN"2"59;
"A"
$PN"1"60;
%"UNIVERSAL_POWER"
"1","(-6575,5925)","0","pure_quanta_power","I34";
;
HDL_POWER"P3V3_AUX"
CDS_LIB"pure_quanta_power";
"A"3;
%"Q_RES"
"2","(-6575,5650)","2","pure_quanta","I35";
;
LOCATION"R2921"
$SEC"1"
CDS_SEC"1"
WATTAGE"1/16W"
MATERIAL"EMPTY"
VALUE"10K"
TOLERANCE"1%"
PACK_TYPE"0402LF"
CDS_LIB"pure_quanta"
PART_NUMBER"CS31002FB08";
"A"
$PN"1"3;
"B"
$PN"2"60;
%"Q_RES"
"2","(-5600,5800)","0","pure_quanta","I37";
;
LOCATION"R2923"
$SEC"1"
CDS_SEC"1"
TOLERANCE"5%"
WATTAGE"1/16W"
VALUE"4.7K"
MATERIAL"EMPTY"
PACK_TYPE"0402LF"
CDS_LIB"pure_quanta"
PART_NUMBER"CS24702JB10";
"A"
$PN"1"4;
"B"
$PN"2"58;
%"UNIVERSAL_POWER"
"1","(-5600,6025)","0","pure_quanta_power","I38";
;
HDL_POWER"P3V3_AUX"
CDS_LIB"pure_quanta_power";
"A"4;
%"Q_RES"
"1","(-3525,875)","0","pure_quanta","I39";
;
LOCATION"R9012"
$SEC"1"
CDS_SEC"1"
VALUE"0"
TOLERANCE"5%"
MATERIAL"CHIP"
PACK_TYPE"0402LF"
WATTAGE"1/16W"
CDS_LIB"pure_quanta"
PART_NUMBER"CS00002JB13";
"B"
$PN"2"32;
"A"
$PN"1"52;
%"UNIVERSAL_POWER"
"1","(-7175,3525)","0","pure_quanta_power","I4";
;
HDL_POWER"P3V3_AUX"
CDS_LIB"pure_quanta_power";
"A"62;
%"Q_RES"
"1","(-3525,975)","0","pure_quanta","I40";
;
LOCATION"R9010"
$SEC"1"
CDS_SEC"1"
MATERIAL"CHIP"
TOLERANCE"5%"
VALUE"0"
CDS_LIB"pure_quanta"
WATTAGE"1/16W"
PACK_TYPE"0402LF"
PART_NUMBER"CS00002JB13";
"B"
$PN"2"37;
"A"
$PN"1"46;
%"Q_RES"
"1","(-3525,1075)","0","pure_quanta","I41";
;
LOCATION"R8004"
$SEC"1"
CDS_SEC"1"
TOLERANCE"5%"
VALUE"0"
MATERIAL"CHIP"
WATTAGE"1/16W"
PACK_TYPE"0402LF"
CDS_LIB"pure_quanta"
PART_NUMBER"CS00002JB13";
"B"
$PN"2"36;
"A"
$PN"1"51;
%"Q_RES"
"1","(-3525,1400)","0","pure_quanta","I42";
;
LOCATION"R9019"
$SEC"1"
CDS_SEC"1"
VALUE"0"
MATERIAL"CHIP"
TOLERANCE"5%"
PACK_TYPE"0402LF"
WATTAGE"1/16W"
CDS_LIB"pure_quanta"
PART_NUMBER"CS00002JB13";
"B"
$PN"2"38;
"A"
$PN"1"50;
%"Q_RES"
"1","(-3525,1500)","0","pure_quanta","I43";
;
LOCATION"R9013"
$SEC"1"
CDS_SEC"1"
MATERIAL"CHIP"
TOLERANCE"5%"
VALUE"0"
CDS_LIB"pure_quanta"
WATTAGE"1/16W"
PACK_TYPE"0402LF"
PART_NUMBER"CS00002JB13";
"B"
$PN"2"33;
"A"
$PN"1"53;
%"Q_RES"
"1","(-3525,1600)","0","pure_quanta","I44";
;
LOCATION"R9018"
$SEC"1"
CDS_SEC"1"
MATERIAL"CHIP"
TOLERANCE"5%"
VALUE"0"
CDS_LIB"pure_quanta"
WATTAGE"1/16W"
PACK_TYPE"0402LF"
PART_NUMBER"CS00002JB13";
"B"
$PN"2"34;
"A"
$PN"1"49;
%"Q_RES"
"1","(-3525,1700)","0","pure_quanta","I45";
;
LOCATION"R9011"
$SEC"1"
CDS_SEC"1"
MATERIAL"CHIP"
VALUE"0"
TOLERANCE"5%"
CDS_LIB"pure_quanta"
WATTAGE"1/16W"
PACK_TYPE"0402LF"
PART_NUMBER"CS00002JB13";
"B"
$PN"2"35;
"A"
$PN"1"48;
%"Q_RES"
"1","(-3525,1825)","0","pure_quanta","I46";
;
LOCATION"R9001"
$SEC"1"
CDS_SEC"1"
MATERIAL"CHIP"
VALUE"0"
TOLERANCE"5%"
PACK_TYPE"0402LF"
WATTAGE"1/16W"
CDS_LIB"pure_quanta"
PART_NUMBER"CS00002JB13";
"B"
$PN"2"9;
"A"
$PN"1"47;
%"Q_RES"
"1","(-3525,2250)","0","pure_quanta","I47";
;
LOCATION"R3518"
$SEC"1"
CDS_SEC"1"
MATERIAL"CHIP"
TOLERANCE"5%"
VALUE"0"
CDS_LIB"pure_quanta"
PACK_TYPE"0402LF"
WATTAGE"1/16W"
PART_NUMBER"CS00002JB13";
"B"
$PN"2"7;
"A"
$PN"1"45;
%"UNIVERSAL_GND"
"1","(-6925,2300)","0","pure_quanta_power","I5";
;
CDS_LIB"pure_quanta_power"
HDL_POWER"GND";
"A"5;
%"Q_RES"
"1","(-3525,2450)","0","pure_quanta","I55";
;
LOCATION"R3517"
$SEC"1"
CDS_SEC"1"
TOLERANCE"5%"
VALUE"0"
MATERIAL"CHIP"
CDS_LIB"pure_quanta"
WATTAGE"1/16W"
PACK_TYPE"0402LF"
PART_NUMBER"CS00002JB13";
"B"
$PN"2"10;
"A"
$PN"1"44;
%"Q_RES"
"1","(-3525,2650)","0","pure_quanta","I56";
;
LOCATION"R3516"
$SEC"1"
CDS_SEC"1"
TOLERANCE"5%"
MATERIAL"CHIP"
VALUE"0"
CDS_LIB"pure_quanta"
PACK_TYPE"0402LF"
WATTAGE"1/16W"
PART_NUMBER"CS00002JB13";
"B"
$PN"2"31;
"A"
$PN"1"41;
%"Q_RES"
"1","(-3525,2850)","0","pure_quanta","I57";
;
LOCATION"R3499"
$SEC"1"
CDS_SEC"1"
TOLERANCE"5%"
MATERIAL"CHIP"
VALUE"0"
WATTAGE"1/16W"
PACK_TYPE"0402LF"
CDS_LIB"pure_quanta"
PART_NUMBER"CS00002JB13";
"B"
$PN"2"8;
"A"
$PN"1"39;
%"Q_RES"
"1","(-3525,3050)","0","pure_quanta","I58";
;
LOCATION"R2983"
$SEC"1"
CDS_SEC"1"
MATERIAL"CHIP"
TOLERANCE"5%"
VALUE"0"
CDS_LIB"pure_quanta"
PACK_TYPE"0402LF"
WATTAGE"1/16W"
PART_NUMBER"CS00002JB13";
"B"
$PN"2"11;
"A"
$PN"1"40;
%"Q_RES"
"1","(-3525,3475)","0","pure_quanta","I59";
;
LOCATION"R2848"
$SEC"1"
CDS_SEC"1"
MATERIAL"CHIP"
VALUE"0"
TOLERANCE"5%"
WATTAGE"1/16W"
PACK_TYPE"0402LF"
CDS_LIB"pure_quanta"
PART_NUMBER"CS00002JB13";
"B"
$PN"2"30;
"A"
$PN"1"42;
%"Q_RES"
"2","(-6925,2525)","0","pure_quanta","I6";
;
LOCATION"R2696"
$SEC"1"
CDS_SEC"1"
MATERIAL"CHIP"
VALUE"1K"
TOLERANCE"1%"
WATTAGE"1/16W"
PACK_TYPE"0402LF"
CDS_LIB"pure_quanta"
PART_NUMBER"CS21002FB06";
"A"
$PN"1"61;
"B"
$PN"2"5;
%"UNIVERSAL_GND"
"1","(-3275,3675)","0","pure_quanta_power","I60";
;
CDS_LIB"pure_quanta_power"
HDL_POWER"GND";
"A"6;
%"Q_CAP"
"1","(-3275,3900)","2","pure_quanta","I61";
;
LOCATION"C1713"
$SEC"1"
CDS_SEC"1"
TOLERANCE"10%"
VOLTAGE"25V"
MATERIAL"X7R"
VALUE"0.1UF"
PACK_TYPE"0402"
CDS_LIB"pure_quanta"
PART_NUMBER"CH4104K1B00";
"B"
$PN"2"6;
"A"
$PN"1"29;
%"UNIVERSAL_POWER"
"1","(-3275,4175)","0","pure_quanta_power","I62";
;
HDL_POWER"P3V3_AUX"
CDS_LIB"pure_quanta_power";
"A"29;
%"Q_RES"
"2","(-6925,3125)","0","pure_quanta","I7";
;
LOCATION"R2695"
$SEC"1"
CDS_SEC"1"
WATTAGE"1/16W"
VALUE"1K"
TOLERANCE"1%"
MATERIAL"EMPTY"
PACK_TYPE"0402LF"
CDS_LIB"pure_quanta"
PART_NUMBER"CS21002FB06";
"A"
$PN"1"62;
"B"
$PN"2"61;
%"Q_RES"
"1","(-3525,3250)","0","pure_quanta","I82";
;
LOCATION"R2982"
$SEC"1"
CDS_SEC"1"
MATERIAL"CHIP"
TOLERANCE"5%"
VALUE"0"
WATTAGE"1/16W"
PACK_TYPE"0402LF"
CDS_LIB"pure_quanta"
PART_NUMBER"CS00002JB13";
"B"
$PN"2"12;
"A"
$PN"1"43;
%"PCA9539RPW"
"1","(-4400,4950)","0","pure_quanta","I83";
;
LOCATION"U181"
SEC"1"
VALUE"PCA9539RPW"
MATERIAL"IC"
PART_TYPE"SMLF"
CDS_LMAN_SYM_OUTLINE"-250,600,250,-600"
NEEDS_NO_SIZE"TRUE"
CDS_LIB"pure_quanta"
SEC_TYPE""
PART_NUMBER"AL009539K07";
"VDD"
$PN"24"29;
"SDA"
$PN"23"25;
"SCL"
$PN"22"26;
"A0"
$PN"21"27;
"IO1_7"
$PN"20"28;
"IO1_6"
$PN"19"18;
"IO1_5"
$PN"18"19;
"IO1_4"
$PN"17"20;
"IO1_3"
$PN"16"21;
"IO1_2"
$PN"15"22;
"IO1_1"
$PN"14"23;
"IO1_0"
$PN"13"24;
"VSS"
$PN"12"2;
"IO0_7"
$PN"11"54;
"IO0_6"
$PN"10"17;
"IO0_5"
$PN"9"56;
"IO0_4"
$PN"8"57;
"IO0_3"
$PN"7"16;
"IO0_2"
$PN"6"15;
"IO0_1"
$PN"5"14;
"IO0_0"
$PN"4"13;
"RESET \B"
$PN"3"59;
"A1"
$PN"2"55;
"INT \B"
$PN"1"58;
END.
